(kicad_pcb
	(version 20260206)
	(generator "pcbnew")
	(generator_version "10.0")
	(general
		(thickness 1.6)
		(legacy_teardrops no)
	)
	(paper "A4")
	(title_block
		(title "Wiwynn_Tioga_Pass_MB.brd")
		(comment 1 "Tioga Pass / footprint 2254 of 4770 (U5D1), pads 2407-2518 of 3647")
	)
	(layers
		(0 "F.Cu" signal "TOP")
		(4 "In1.Cu" signal "L2GND")
		(6 "In2.Cu" signal "L3")
		(8 "In3.Cu" signal "L4GND")
		(10 "In4.Cu" signal "L5")
		(12 "In5.Cu" signal "L6GND")
		(14 "In6.Cu" signal "L7VCC")
		(16 "In7.Cu" signal "L8VCC")
		(18 "In8.Cu" signal "L9GND")
		(20 "In9.Cu" signal "L10")
		(22 "In10.Cu" signal "L11GND")
		(24 "In11.Cu" signal "L12")
		(26 "In12.Cu" signal "L13GND")
		(2 "B.Cu" signal "BOTTOM")
		(9 "F.Adhes" user "F.Adhesive")
		(11 "B.Adhes" user "B.Adhesive")
		(13 "F.Paste" user "Package Geometry/Pastemask Top")
		(15 "B.Paste" user "Package Geometry/Pastemask Bottom")
		(5 "F.SilkS" user "Ref Des/Silkscreen Top")
		(7 "B.SilkS" user "Ref Des/Silkscreen Bottom")
		(1 "F.Mask" user "Board Geometry/Soldermask Top")
		(3 "B.Mask" user "Board Geometry/Soldermask Bottom")
		(17 "Dwgs.User" user "User.Drawings")
		(19 "Cmts.User" user "User.Comments")
		(21 "Eco1.User" user "User.Eco1")
		(23 "Eco2.User" user "User.Eco2")
		(25 "Edge.Cuts" user "Board Geometry/Outline")
		(27 "Margin" user)
		(31 "F.CrtYd" user "Package Geometry/Place Bound Top")
		(29 "B.CrtYd" user "Package Geometry/Place Bound Bottom")
		(35 "F.Fab" user "Ref Des/Assembly Top")
		(33 "B.Fab" user "Ref Des/Assembly Bottom")
	)
	(footprint ""
		(layer "F.Cu")
		(at 270.000222 -76.550012 180)
		(property "Reference" "U5D1"
			(at 19.124422 31.601918 0)
			(unlocked yes)
			(layer "F.SilkS")
			(effects
				(font
					(size 0.7874 0.5842)
					(thickness 0.1524)
				)
			)
		)
		(property "Value" ""
			(at 0 0 180)
			(layer "F.Fab")
			(effects
				(font
					(size 1.27 1.27)
				)
			)
		)
		(duplicate_pad_numbers_are_jumpers no)
		(pad "DM15" smd circle
			(at -25.231598 19.968972)
			(size 0.4318 0.4318)
			(layers "F.Cu" "F.Mask" "F.Paste")
			(net "GND")
		)
		(pad "DM17" smd circle
			(at -23.514558 19.968972)
			(size 0.4318 0.4318)
			(layers "F.Cu" "F.Mask" "F.Paste")
			(net "PVCCIO_CPU0")
		)
		(pad "DM19" smd circle
			(at -21.797518 19.968972)
			(size 0.4318 0.4318)
			(layers "F.Cu" "F.Mask" "F.Paste")
			(net "GND")
		)
		(pad "DM21" smd circle
			(at -20.080478 19.968972)
			(size 0.4318 0.4318)
			(layers "F.Cu" "F.Mask" "F.Paste")
			(net "TP_CPU0_UPI2_RSVD_CC10")
		)
		(pad "DM23" smd circle
			(at -18.363438 19.968972)
			(size 0.4318 0.4318)
			(layers "F.Cu" "F.Mask" "F.Paste")
			(net "M_D_DQS_DN<16>")
		)
		(pad "DM25" smd circle
			(at -16.646398 19.968972)
			(size 0.4318 0.4318)
			(layers "F.Cu" "F.Mask" "F.Paste")
			(net "GND")
		)
		(pad "DM27" smd circle
			(at -14.929612 19.968972)
			(size 0.4318 0.4318)
			(layers "F.Cu" "F.Mask" "F.Paste")
			(net "GND")
		)
		(pad "DM29" smd circle
			(at -13.212572 19.968972)
			(size 0.4318 0.4318)
			(layers "F.Cu" "F.Mask" "F.Paste")
			(net "M_D_DQS_DN<15>")
		)
		(pad "DM31" smd circle
			(at -11.495532 19.968972)
			(size 0.4318 0.4318)
			(layers "F.Cu" "F.Mask" "F.Paste")
			(net "GND")
		)
		(pad "DM33" smd circle
			(at -9.778492 19.968972)
			(size 0.4318 0.4318)
			(layers "F.Cu" "F.Mask" "F.Paste")
			(net "GND")
		)
		(pad "DM35" smd circle
			(at -8.061452 19.968972)
			(size 0.4318 0.4318)
			(layers "F.Cu" "F.Mask" "F.Paste")
			(net "M_D_DQS_DP<14>")
		)
		(pad "DM37" smd circle
			(at -6.344412 19.968972)
			(size 0.4318 0.4318)
			(layers "F.Cu" "F.Mask" "F.Paste")
			(net "GND")
		)
		(pad "DM39" smd circle
			(at -4.627626 19.968972)
			(size 0.4318 0.4318)
			(layers "F.Cu" "F.Mask" "F.Paste")
			(net "GND")
		)
		(pad "DM41" smd circle
			(at -2.910586 19.968972)
			(size 0.4318 0.4318)
			(layers "F.Cu" "F.Mask" "F.Paste")
			(net "M_E_DQS_DP<13>")
		)
		(pad "DM45" smd circle
			(at 2.052066 18.168874)
			(size 0.4318 0.4318)
			(layers "F.Cu" "F.Mask" "F.Paste")
			(net "M_F_CS_N<6>")
		)
		(pad "DM47" smd circle
			(at 3.769106 18.168874)
			(size 0.4318 0.4318)
			(layers "F.Cu" "F.Mask" "F.Paste")
			(net "M_E_ODT<3>")
		)
		(pad "DM49" smd circle
			(at 5.485892 18.168874)
			(size 0.4318 0.4318)
			(layers "F.Cu" "F.Mask" "F.Paste")
			(net "M_E_CS_N<5>")
		)
		(pad "DM51" smd circle
			(at 7.202932 18.168874)
			(size 0.4318 0.4318)
			(layers "F.Cu" "F.Mask" "F.Paste")
			(net "M_E_MA<14>")
		)
		(pad "DM53" smd circle
			(at 8.919972 18.168874)
			(size 0.4318 0.4318)
			(layers "F.Cu" "F.Mask" "F.Paste")
			(net "M_E_BA<0>")
		)
		(pad "DM55" smd circle
			(at 10.637012 18.168874)
			(size 0.4318 0.4318)
			(layers "F.Cu" "F.Mask" "F.Paste")
			(net "M_E_CLK_DN<0>")
		)
		(pad "DM57" smd circle
			(at 12.354052 18.168874)
			(size 0.4318 0.4318)
			(layers "F.Cu" "F.Mask" "F.Paste")
			(net "M_E_CLK_DN<2>")
		)
		(pad "DM59" smd circle
			(at 14.071092 18.168874)
			(size 0.4318 0.4318)
			(layers "F.Cu" "F.Mask" "F.Paste")
			(net "M_E_MA<6>")
		)
		(pad "DM61" smd circle
			(at 15.787878 18.168874)
			(size 0.4318 0.4318)
			(layers "F.Cu" "F.Mask" "F.Paste")
			(net "M_E_BG<1>")
		)
		(pad "DM63" smd circle
			(at 17.504918 18.168874)
			(size 0.4318 0.4318)
			(layers "F.Cu" "F.Mask" "F.Paste")
			(net "M_E_CKE<0>")
		)
		(pad "DM65" smd circle
			(at 19.221958 18.168874)
			(size 0.4318 0.4318)
			(layers "F.Cu" "F.Mask" "F.Paste")
			(net "GND")
		)
		(pad "DM67" smd circle
			(at 20.938998 18.168874)
			(size 0.4318 0.4318)
			(layers "F.Cu" "F.Mask" "F.Paste")
			(net "TP_CPU0_RSVD_33")
		)
		(pad "DM69" smd circle
			(at 22.656038 18.168874)
			(size 0.4318 0.4318)
			(layers "F.Cu" "F.Mask" "F.Paste")
			(net "M_F_DQ<18>")
		)
		(pad "DM71" smd circle
			(at 24.373078 18.168874)
			(size 0.4318 0.4318)
			(layers "F.Cu" "F.Mask" "F.Paste")
			(net "M_F_DQ<23>")
		)
		(pad "DM73" smd circle
			(at 26.090118 18.168874)
			(size 0.4318 0.4318)
			(layers "F.Cu" "F.Mask" "F.Paste")
			(net "GND")
		)
		(pad "DM75" smd circle
			(at 27.806904 18.168874)
			(size 0.4318 0.4318)
			(layers "F.Cu" "F.Mask" "F.Paste")
			(net "M_D_DQS_DP<12>")
		)
		(pad "DM77" smd circle
			(at 29.523944 18.168874)
			(size 0.4318 0.4318)
			(layers "F.Cu" "F.Mask" "F.Paste")
			(net "GND")
		)
		(pad "DM79" smd circle
			(at 31.240984 18.168874)
			(size 0.4318 0.4318)
			(layers "F.Cu" "F.Mask" "F.Paste")
			(net "M_D_DQ<16>")
		)
		(pad "DM81" smd circle
			(at 32.958024 18.168874)
			(size 0.4318 0.4318)
			(layers "F.Cu" "F.Mask" "F.Paste")
			(net "M_D_DQS_DP<2>")
		)
		(pad "DM83" smd circle
			(at 34.675064 18.168874)
			(size 0.4318 0.4318)
			(layers "F.Cu" "F.Mask" "F.Paste")
			(net "GND")
		)
		(pad "DM85" smd custom
			(at 36.392104 18.168874 270)
			(size 0.10795 0.10795)
			(layers "F.Cu" "F.Mask" "F.Paste")
			(net "M_D_DQS_DN<10>")
			(options
				(clearance outline)
				(anchor circle)
			)
			(primitives
				(gr_poly
					(pts
						(arc
							(start 0.2159 -0.0381)
							(mid 0 -0.254)
							(end -0.2159 -0.0381)
						)
						(arc
							(start -0.2159 0.0381)
							(mid 0 0.254)
							(end 0.2159 0.0381)
						)
					)
					(width 0)
					(fill yes)
				)
			)
		)
		(pad "DN2" smd custom
			(at -36.392104 20.464526 90)
			(size 0.10795 0.10795)
			(layers "F.Cu" "F.Mask" "F.Paste")
			(net "GND")
			(options
				(clearance outline)
				(anchor circle)
			)
			(primitives
				(gr_poly
					(pts
						(arc
							(start 0.2159 -0.0381)
							(mid 0 -0.254)
							(end -0.2159 -0.0381)
						)
						(arc
							(start -0.2159 0.0381)
							(mid 0 0.254)
							(end 0.2159 0.0381)
						)
					)
					(width 0)
					(fill yes)
				)
			)
		)
		(pad "DN4" smd circle
			(at -34.675064 20.464526)
			(size 0.4318 0.4318)
			(layers "F.Cu" "F.Mask" "F.Paste")
			(net "P3E_CPU0_PE1_SS_TXN<7>")
		)
		(pad "DN6" smd circle
			(at -32.958024 20.464526)
			(size 0.4318 0.4318)
			(layers "F.Cu" "F.Mask" "F.Paste")
			(net "P3E_CPU0_PE3_OCP_TXP<8>")
		)
		(pad "DN8" smd circle
			(at -31.240984 20.464526)
			(size 0.4318 0.4318)
			(layers "F.Cu" "F.Mask" "F.Paste")
			(net "PVCCIO_CPU0")
		)
		(pad "DN10" smd circle
			(at -29.523944 20.464526)
			(size 0.4318 0.4318)
			(layers "F.Cu" "F.Mask" "F.Paste")
			(net "P3E_CPU0_PE1_PCH_RXP<9>")
		)
		(pad "DN12" smd circle
			(at -27.806904 20.464526)
			(size 0.4318 0.4318)
			(layers "F.Cu" "F.Mask" "F.Paste")
			(net "GND")
		)
		(pad "DN14" smd circle
			(at -26.090118 20.464526)
			(size 0.4318 0.4318)
			(layers "F.Cu" "F.Mask" "F.Paste")
			(net "P3E_CPU0_PE3_OCP_RXN<6>")
		)
		(pad "DN16" smd circle
			(at -24.373078 20.464526)
			(size 0.4318 0.4318)
			(layers "F.Cu" "F.Mask" "F.Paste")
			(net "P3E_CPU0_PE3_OCP_RXP<4>")
		)
		(pad "DN18" smd circle
			(at -22.656038 20.464526)
			(size 0.4318 0.4318)
			(layers "F.Cu" "F.Mask" "F.Paste")
			(net "GND")
		)
		(pad "DN20" smd circle
			(at -20.938998 20.464526)
			(size 0.4318 0.4318)
			(layers "F.Cu" "F.Mask" "F.Paste")
			(net "TP_CPU0_UPI2_RSVD_CB11")
		)
		(pad "DN22" smd circle
			(at -19.221958 20.464526)
			(size 0.4318 0.4318)
			(layers "F.Cu" "F.Mask" "F.Paste")
			(net "GND")
		)
		(pad "DN24" smd circle
			(at -17.504918 20.464526)
			(size 0.4318 0.4318)
			(layers "F.Cu" "F.Mask" "F.Paste")
			(net "M_D_DQ<56>")
		)
		(pad "DN26" smd circle
			(at -15.787878 20.464526)
			(size 0.4318 0.4318)
			(layers "F.Cu" "F.Mask" "F.Paste")
			(net "GND")
		)
		(pad "DN28" smd circle
			(at -14.071092 20.464526)
			(size 0.4318 0.4318)
			(layers "F.Cu" "F.Mask" "F.Paste")
			(net "M_D_DQ<54>")
		)
		(pad "DN30" smd circle
			(at -12.354052 20.464526)
			(size 0.4318 0.4318)
			(layers "F.Cu" "F.Mask" "F.Paste")
			(net "M_D_DQ<48>")
		)
		(pad "DN32" smd circle
			(at -10.637012 20.464526)
			(size 0.4318 0.4318)
			(layers "F.Cu" "F.Mask" "F.Paste")
			(net "GND")
		)
		(pad "DN34" smd circle
			(at -8.919972 20.464526)
			(size 0.4318 0.4318)
			(layers "F.Cu" "F.Mask" "F.Paste")
			(net "M_D_DQ<46>")
		)
		(pad "DN36" smd circle
			(at -7.202932 20.464526)
			(size 0.4318 0.4318)
			(layers "F.Cu" "F.Mask" "F.Paste")
			(net "M_D_DQ<40>")
		)
		(pad "DN38" smd circle
			(at -5.485892 20.464526)
			(size 0.4318 0.4318)
			(layers "F.Cu" "F.Mask" "F.Paste")
			(net "GND")
		)
		(pad "DN40" smd circle
			(at -3.769106 20.464526)
			(size 0.4318 0.4318)
			(layers "F.Cu" "F.Mask" "F.Paste")
			(net "M_E_DQ<38>")
		)
		(pad "DN42" smd circle
			(at -2.052066 20.464526)
			(size 0.4318 0.4318)
			(layers "F.Cu" "F.Mask" "F.Paste")
			(net "M_E_DQ<37>")
		)
		(pad "DN44" smd circle
			(at 1.193546 18.664428)
			(size 0.508 0.508)
			(layers "F.Cu" "F.Mask" "F.Paste")
			(net "GND")
		)
		(pad "DN46" smd circle
			(at 2.910586 18.664428)
			(size 0.4318 0.4318)
			(layers "F.Cu" "F.Mask" "F.Paste")
			(net "M_E_CS_N<7>")
		)
		(pad "DN48" smd circle
			(at 4.627626 18.664428)
			(size 0.4318 0.4318)
			(layers "F.Cu" "F.Mask" "F.Paste")
			(net "M_E_ODT<1>")
		)
		(pad "DN50" smd circle
			(at 6.344412 18.664428)
			(size 0.4318 0.4318)
			(layers "F.Cu" "F.Mask" "F.Paste")
			(net "M_E_CS_N<1>")
		)
		(pad "DN52" smd circle
			(at 8.061452 18.664428)
			(size 0.4318 0.4318)
			(layers "F.Cu" "F.Mask" "F.Paste")
			(net "M_E_MA<16>")
		)
		(pad "DN54" smd circle
			(at 9.778492 18.664428)
			(size 0.4318 0.4318)
			(layers "F.Cu" "F.Mask" "F.Paste")
			(net "M_E_CLK_DP<0>")
		)
		(pad "DN56" smd circle
			(at 11.495532 18.664428)
			(size 0.4318 0.4318)
			(layers "F.Cu" "F.Mask" "F.Paste")
			(net "M_E_CLK_DP<2>")
		)
		(pad "DN58" smd circle
			(at 13.212572 18.664428)
			(size 0.4318 0.4318)
			(layers "F.Cu" "F.Mask" "F.Paste")
			(net "M_E_MA<5>")
		)
		(pad "DN60" smd circle
			(at 14.929612 18.664428)
			(size 0.4318 0.4318)
			(layers "F.Cu" "F.Mask" "F.Paste")
			(net "M_E_MA<12>")
		)
		(pad "DN62" smd circle
			(at 16.646398 18.664428)
			(size 0.4318 0.4318)
			(layers "F.Cu" "F.Mask" "F.Paste")
			(net "TP_CPU0_RSVD_32")
		)
		(pad "DN64" smd circle
			(at 18.363438 18.664428)
			(size 0.4318 0.4318)
			(layers "F.Cu" "F.Mask" "F.Paste")
			(net "M_E_CKE<1>")
		)
		(pad "DN66" smd circle
			(at 20.080478 18.664428)
			(size 0.4318 0.4318)
			(layers "F.Cu" "F.Mask" "F.Paste")
			(net "TP_CPU0_RSVD_31")
		)
		(pad "DN68" smd circle
			(at 21.797518 18.664428)
			(size 0.4318 0.4318)
			(layers "F.Cu" "F.Mask" "F.Paste")
			(net "GND")
		)
		(pad "DN70" smd circle
			(at 23.514558 18.664428)
			(size 0.4318 0.4318)
			(layers "F.Cu" "F.Mask" "F.Paste")
			(net "M_F_DQ<19>")
		)
		(pad "DN72" smd circle
			(at 25.231598 18.664428)
			(size 0.4318 0.4318)
			(layers "F.Cu" "F.Mask" "F.Paste")
			(net "GND")
		)
		(pad "DN74" smd circle
			(at 26.948384 18.664428)
			(size 0.4318 0.4318)
			(layers "F.Cu" "F.Mask" "F.Paste")
			(net "M_D_DQ<30>")
		)
		(pad "DN76" smd circle
			(at 28.665424 18.664428)
			(size 0.4318 0.4318)
			(layers "F.Cu" "F.Mask" "F.Paste")
			(net "M_D_DQ<24>")
		)
		(pad "DN78" smd circle
			(at 30.382464 18.664428)
			(size 0.4318 0.4318)
			(layers "F.Cu" "F.Mask" "F.Paste")
			(net "GND")
		)
		(pad "DN80" smd circle
			(at 32.099504 18.664428)
			(size 0.4318 0.4318)
			(layers "F.Cu" "F.Mask" "F.Paste")
			(net "M_D_DQS_DN<11>")
		)
		(pad "DN82" smd circle
			(at 33.816544 18.664428)
			(size 0.4318 0.4318)
			(layers "F.Cu" "F.Mask" "F.Paste")
			(net "M_D_DQ<23>")
		)
		(pad "DN84" smd circle
			(at 35.533584 18.664428)
			(size 0.4318 0.4318)
			(layers "F.Cu" "F.Mask" "F.Paste")
			(net "M_D_DQS_DN<1>")
		)
		(pad "DP3" smd circle
			(at -35.533584 20.959572)
			(size 0.4318 0.4318)
			(layers "F.Cu" "F.Mask" "F.Paste")
			(net "P3E_CPU0_PE1_SS_TXP<7>")
		)
		(pad "DP5" smd circle
			(at -33.816544 20.959572)
			(size 0.4318 0.4318)
			(layers "F.Cu" "F.Mask" "F.Paste")
			(net "P3E_CPU0_PE3_OCP_TXN<9>")
		)
		(pad "DP7" smd circle
			(at -32.099504 20.959572)
			(size 0.4318 0.4318)
			(layers "F.Cu" "F.Mask" "F.Paste")
			(net "P3E_CPU0_PE3_OCP_TXP<7>")
		)
		(pad "DP9" smd circle
			(at -30.382464 20.959572)
			(size 0.4318 0.4318)
			(layers "F.Cu" "F.Mask" "F.Paste")
			(net "GND")
		)
		(pad "DP11" smd circle
			(at -28.665424 20.959572)
			(size 0.4318 0.4318)
			(layers "F.Cu" "F.Mask" "F.Paste")
			(net "P3E_CPU0_PE1_PCH_RXN<9>")
		)
		(pad "DP13" smd circle
			(at -26.948384 20.959572)
			(size 0.4318 0.4318)
			(layers "F.Cu" "F.Mask" "F.Paste")
			(net "P3E_CPU0_PE1_PCH_RXP<11>")
		)
		(pad "DP15" smd circle
			(at -25.231598 20.959572)
			(size 0.4318 0.4318)
			(layers "F.Cu" "F.Mask" "F.Paste")
			(net "P3E_CPU0_PE3_OCP_RXP<5>")
		)
		(pad "DP17" smd circle
			(at -23.514558 20.959572)
			(size 0.4318 0.4318)
			(layers "F.Cu" "F.Mask" "F.Paste")
			(net "TP_CPU0_RSVD_30")
		)
		(pad "DP19" smd circle
			(at -21.797518 20.959572)
			(size 0.4318 0.4318)
			(layers "F.Cu" "F.Mask" "F.Paste")
			(net "PVCCIO_CPU0")
		)
		(pad "DP21" smd circle
			(at -20.080478 20.959572)
			(size 0.4318 0.4318)
			(layers "F.Cu" "F.Mask" "F.Paste")
			(net "TP_CPU0_UPI2_RSVD_CA12")
		)
		(pad "DP23" smd circle
			(at -18.363438 20.959572)
			(size 0.4318 0.4318)
			(layers "F.Cu" "F.Mask" "F.Paste")
			(net "M_D_DQS_DP<16>")
		)
		(pad "DP25" smd circle
			(at -16.646398 20.959572)
			(size 0.4318 0.4318)
			(layers "F.Cu" "F.Mask" "F.Paste")
			(net "M_D_DQ<60>")
		)
		(pad "DP27" smd circle
			(at -14.929612 20.959572)
			(size 0.4318 0.4318)
			(layers "F.Cu" "F.Mask" "F.Paste")
			(net "M_D_DQ<50>")
		)
		(pad "DP29" smd circle
			(at -13.212572 20.959572)
			(size 0.4318 0.4318)
			(layers "F.Cu" "F.Mask" "F.Paste")
			(net "M_D_DQS_DP<15>")
		)
		(pad "DP31" smd circle
			(at -11.495532 20.959572)
			(size 0.4318 0.4318)
			(layers "F.Cu" "F.Mask" "F.Paste")
			(net "M_D_DQ<52>")
		)
		(pad "DP33" smd circle
			(at -9.778492 20.959572)
			(size 0.4318 0.4318)
			(layers "F.Cu" "F.Mask" "F.Paste")
			(net "M_D_DQ<42>")
		)
		(pad "DP35" smd circle
			(at -8.061452 20.959572)
			(size 0.4318 0.4318)
			(layers "F.Cu" "F.Mask" "F.Paste")
			(net "M_D_DQS_DN<14>")
		)
		(pad "DP37" smd circle
			(at -6.344412 20.959572)
			(size 0.4318 0.4318)
			(layers "F.Cu" "F.Mask" "F.Paste")
			(net "M_D_DQ<44>")
		)
		(pad "DP39" smd circle
			(at -4.627626 20.959572)
			(size 0.4318 0.4318)
			(layers "F.Cu" "F.Mask" "F.Paste")
			(net "M_E_DQ<34>")
		)
		(pad "DP41" smd circle
			(at -2.910586 20.959572)
			(size 0.4318 0.4318)
			(layers "F.Cu" "F.Mask" "F.Paste")
			(net "M_E_DQS_DN<13>")
		)
		(pad "DP45" smd circle
			(at 2.052066 19.159474)
			(size 0.4318 0.4318)
			(layers "F.Cu" "F.Mask" "F.Paste")
			(net "GND")
		)
		(pad "DP47" smd circle
			(at 3.769106 19.159474)
			(size 0.4318 0.4318)
			(layers "F.Cu" "F.Mask" "F.Paste")
			(net "GND")
		)
		(pad "DP49" smd circle
			(at 5.485892 19.159474)
			(size 0.4318 0.4318)
			(layers "F.Cu" "F.Mask" "F.Paste")
			(net "GND")
		)
		(pad "DP51" smd circle
			(at 7.202932 19.159474)
			(size 0.4318 0.4318)
			(layers "F.Cu" "F.Mask" "F.Paste")
			(net "GND")
		)
		(pad "DP53" smd circle
			(at 8.919972 19.159474)
			(size 0.4318 0.4318)
			(layers "F.Cu" "F.Mask" "F.Paste")
			(net "GND")
		)
		(pad "DP55" smd circle
			(at 10.637012 19.159474)
			(size 0.4318 0.4318)
			(layers "F.Cu" "F.Mask" "F.Paste")
			(net "GND")
		)
		(pad "DP57" smd circle
			(at 12.354052 19.159474)
			(size 0.4318 0.4318)
			(layers "F.Cu" "F.Mask" "F.Paste")
			(net "GND")
		)
		(pad "DP59" smd circle
			(at 14.071092 19.159474)
			(size 0.4318 0.4318)
			(layers "F.Cu" "F.Mask" "F.Paste")
			(net "GND")
		)
		(pad "DP61" smd circle
			(at 15.787878 19.159474)
			(size 0.4318 0.4318)
			(layers "F.Cu" "F.Mask" "F.Paste")
			(net "GND")
		)
		(pad "DP63" smd circle
			(at 17.504918 19.159474)
			(size 0.4318 0.4318)
			(layers "F.Cu" "F.Mask" "F.Paste")
			(net "GND")
		)
		(pad "DP65" smd circle
			(at 19.221958 19.159474)
			(size 0.4318 0.4318)
			(layers "F.Cu" "F.Mask" "F.Paste")
			(net "TP_CPU0_RSVD_29")
		)
		(pad "DP67" smd circle
			(at 20.938998 19.159474)
			(size 0.4318 0.4318)
			(layers "F.Cu" "F.Mask" "F.Paste")
			(net "GND")
		)
		(pad "DP69" smd circle
			(at 22.656038 19.159474)
			(size 0.4318 0.4318)
			(layers "F.Cu" "F.Mask" "F.Paste")
			(net "GND")
		)
		(pad "DP71" smd circle
			(at 24.373078 19.159474)
			(size 0.4318 0.4318)
			(layers "F.Cu" "F.Mask" "F.Paste")
			(net "GND")
		)
		(pad "DP73" smd circle
			(at 26.090118 19.159474)
			(size 0.4318 0.4318)
			(layers "F.Cu" "F.Mask" "F.Paste")
			(net "M_D_DQ<26>")
		)
	)
)
